(kicad_pcb
	(version 20260206)
	(generator "pcbnew")
	(generator_version "10.0")
	(general
		(thickness 1.6)
		(legacy_teardrops no)
	)
	(paper "A4")
	(title_block
		(title "12092022_DA0F0TMDCD0_F0T_Management_Board_D_brd_V3_OCP.brd")
		(comment 1 "Grand Teton / footprints 104-109 of 1440")
	)
	(layers
		(0 "F.Cu" signal "TOP")
		(4 "In1.Cu" signal "GND")
		(6 "In2.Cu" signal "IN1")
		(8 "In3.Cu" signal "GND1")
		(10 "In4.Cu" signal "IN2")
		(12 "In5.Cu" signal "VCC")
		(14 "In6.Cu" signal "VCC1")
		(16 "In7.Cu" signal "IN3")
		(18 "In8.Cu" signal "GND2")
		(20 "In9.Cu" signal "IN4")
		(22 "In10.Cu" signal "GND3")
		(2 "B.Cu" signal "BOTTOM")
		(9 "F.Adhes" user "F.Adhesive")
		(11 "B.Adhes" user "B.Adhesive")
		(13 "F.Paste" user "Package Geometry/Pastemask Top")
		(15 "B.Paste" user "Package Geometry/Pastemask Bottom")
		(5 "F.SilkS" user "Ref Des/Silkscreen Top")
		(7 "B.SilkS" user "Ref Des/Silkscreen Bottom")
		(1 "F.Mask" user "Board Geometry/Soldermask Top")
		(3 "B.Mask" user "Board Geometry/Soldermask Bottom")
		(17 "Dwgs.User" user "User.Drawings")
		(19 "Cmts.User" user "User.Comments")
		(21 "Eco1.User" user "User.Eco1")
		(23 "Eco2.User" user "User.Eco2")
		(25 "Edge.Cuts" user "Board Geometry/Outline")
		(27 "Margin" user)
		(31 "F.CrtYd" user "Package Geometry/Place Bound Top")
		(29 "B.CrtYd" user "Package Geometry/Place Bound Bottom")
		(35 "F.Fab" user "Ref Des/Assembly Top")
		(33 "B.Fab" user "Ref Des/Assembly Bottom")
	)
	(footprint ""
		(layer "F.Cu")
		(at 30.564074 -61.341 -90)
		(property "Reference" "R72"
			(at 0 0 270)
			(layer "F.SilkS")
			(hide yes)
			(effects
				(font
					(size 1.27 1.27)
				)
			)
		)
		(property "Value" ""
			(at 0 0 270)
			(layer "F.Fab")
			(effects
				(font
					(size 1.27 1.27)
				)
			)
		)
		(duplicate_pad_numbers_are_jumpers no)
		(fp_line
			(start -0.7874 0.4064)
			(end -0.7874 -0.4064)
			(stroke
				(width 0.1524)
				(type default)
			)
			(layer "F.SilkS")
		)
		(fp_line
			(start 0.7874 0.4064)
			(end -0.7874 0.4064)
			(stroke
				(width 0.1524)
				(type default)
			)
			(layer "F.SilkS")
		)
		(fp_line
			(start -0.7874 -0.4064)
			(end 0.7874 -0.4064)
			(stroke
				(width 0.1524)
				(type default)
			)
			(layer "F.SilkS")
		)
		(fp_line
			(start 0.7874 -0.4064)
			(end 0.7874 0.4064)
			(stroke
				(width 0.1524)
				(type default)
			)
			(layer "F.SilkS")
		)
		(fp_line
			(start -0.67945 0.3048)
			(end -0.67945 -0.305054)
			(stroke
				(width 0.1)
				(type default)
			)
			(layer "F.Fab")
		)
		(fp_line
			(start -0.12065 0.3048)
			(end -0.67945 0.3048)
			(stroke
				(width 0.1)
				(type default)
			)
			(layer "F.Fab")
		)
		(fp_line
			(start 0.120396 0.3048)
			(end 0.120396 0.2794)
			(stroke
				(width 0.1)
				(type default)
			)
			(layer "F.Fab")
		)
		(fp_line
			(start 0.67945 0.3048)
			(end 0.120396 0.3048)
			(stroke
				(width 0.1)
				(type default)
			)
			(layer "F.Fab")
		)
		(fp_line
			(start -0.12065 0.2794)
			(end -0.12065 0.3048)
			(stroke
				(width 0.1)
				(type default)
			)
			(layer "F.Fab")
		)
		(fp_line
			(start 0.120396 0.2794)
			(end -0.12065 0.2794)
			(stroke
				(width 0.1)
				(type default)
			)
			(layer "F.Fab")
		)
		(fp_line
			(start -0.12065 -0.2794)
			(end 0.12065 -0.2794)
			(stroke
				(width 0.1)
				(type default)
			)
			(layer "F.Fab")
		)
		(fp_line
			(start 0.12065 -0.2794)
			(end 0.12065 -0.3048)
			(stroke
				(width 0.1)
				(type default)
			)
			(layer "F.Fab")
		)
		(fp_line
			(start 0.12065 -0.3048)
			(end 0.67945 -0.3048)
			(stroke
				(width 0.1)
				(type default)
			)
			(layer "F.Fab")
		)
		(fp_line
			(start 0.67945 -0.3048)
			(end 0.67945 0.3048)
			(stroke
				(width 0.1)
				(type default)
			)
			(layer "F.Fab")
		)
		(fp_line
			(start -0.67945 -0.305054)
			(end -0.12065 -0.305054)
			(stroke
				(width 0.1)
				(type default)
			)
			(layer "F.Fab")
		)
		(fp_line
			(start -0.12065 -0.305054)
			(end -0.12065 -0.2794)
			(stroke
				(width 0.1)
				(type default)
			)
			(layer "F.Fab")
		)
		(pad "1" smd circle
			(at -0.40005 0 270)
			(size 0 0)
			(layers "F.Cu" "F.Mask" "F.Paste")
			(net "P3V3_AUX")
		)
		(pad "2" smd circle
			(at 0.40005 0 270)
			(size 0 0)
			(layers "F.Cu" "F.Mask" "F.Paste")
			(net "UART_BMC_5_RXD_BUF1")
		)
	)
	(footprint ""
		(layer "F.Cu")
		(at 23.241 -68.834 90)
		(property "Reference" "R57"
			(at 0 0 90)
			(layer "F.SilkS")
			(hide yes)
			(effects
				(font
					(size 1.27 1.27)
				)
			)
		)
		(property "Value" ""
			(at 0 0 90)
			(layer "F.Fab")
			(effects
				(font
					(size 1.27 1.27)
				)
			)
		)
		(duplicate_pad_numbers_are_jumpers no)
		(fp_line
			(start 0.7874 -0.4064)
			(end 0.7874 0.4064)
			(stroke
				(width 0.1524)
				(type default)
			)
			(layer "F.SilkS")
		)
		(fp_line
			(start -0.7874 -0.4064)
			(end 0.7874 -0.4064)
			(stroke
				(width 0.1524)
				(type default)
			)
			(layer "F.SilkS")
		)
		(fp_line
			(start 0.7874 0.4064)
			(end -0.7874 0.4064)
			(stroke
				(width 0.1524)
				(type default)
			)
			(layer "F.SilkS")
		)
		(fp_line
			(start -0.7874 0.4064)
			(end -0.7874 -0.4064)
			(stroke
				(width 0.1524)
				(type default)
			)
			(layer "F.SilkS")
		)
		(fp_line
			(start -0.12065 -0.305054)
			(end -0.12065 -0.2794)
			(stroke
				(width 0.1)
				(type default)
			)
			(layer "F.Fab")
		)
		(fp_line
			(start -0.67945 -0.305054)
			(end -0.12065 -0.305054)
			(stroke
				(width 0.1)
				(type default)
			)
			(layer "F.Fab")
		)
		(fp_line
			(start 0.67945 -0.3048)
			(end 0.67945 0.3048)
			(stroke
				(width 0.1)
				(type default)
			)
			(layer "F.Fab")
		)
		(fp_line
			(start 0.12065 -0.3048)
			(end 0.67945 -0.3048)
			(stroke
				(width 0.1)
				(type default)
			)
			(layer "F.Fab")
		)
		(fp_line
			(start 0.12065 -0.2794)
			(end 0.12065 -0.3048)
			(stroke
				(width 0.1)
				(type default)
			)
			(layer "F.Fab")
		)
		(fp_line
			(start -0.12065 -0.2794)
			(end 0.12065 -0.2794)
			(stroke
				(width 0.1)
				(type default)
			)
			(layer "F.Fab")
		)
		(fp_line
			(start 0.120396 0.2794)
			(end -0.12065 0.2794)
			(stroke
				(width 0.1)
				(type default)
			)
			(layer "F.Fab")
		)
		(fp_line
			(start -0.12065 0.2794)
			(end -0.12065 0.3048)
			(stroke
				(width 0.1)
				(type default)
			)
			(layer "F.Fab")
		)
		(fp_line
			(start 0.67945 0.3048)
			(end 0.120396 0.3048)
			(stroke
				(width 0.1)
				(type default)
			)
			(layer "F.Fab")
		)
		(fp_line
			(start 0.120396 0.3048)
			(end 0.120396 0.2794)
			(stroke
				(width 0.1)
				(type default)
			)
			(layer "F.Fab")
		)
		(fp_line
			(start -0.12065 0.3048)
			(end -0.67945 0.3048)
			(stroke
				(width 0.1)
				(type default)
			)
			(layer "F.Fab")
		)
		(fp_line
			(start -0.67945 0.3048)
			(end -0.67945 -0.305054)
			(stroke
				(width 0.1)
				(type default)
			)
			(layer "F.Fab")
		)
		(pad "1" smd circle
			(at -0.40005 0 90)
			(size 0 0)
			(layers "F.Cu" "F.Mask" "F.Paste")
			(net "BSM_PRSNT_R_N")
		)
		(pad "2" smd circle
			(at 0.40005 0 90)
			(size 0 0)
			(layers "F.Cu" "F.Mask" "F.Paste")
			(net "BSM_PRSNT_N")
		)
	)
	(footprint ""
		(layer "F.Cu")
		(at 51.7525 -92.837 90)
		(property "Reference" "Q3"
			(at 1.29413 2.2225 0)
			(unlocked yes)
			(layer "F.SilkS")
			(effects
				(font
					(size 0.7874 0.5842)
					(thickness 0.1524)
				)
				(justify left)
			)
		)
		(property "Value" ""
			(at 0 0 90)
			(layer "F.Fab")
			(effects
				(font
					(size 1.27 1.27)
				)
			)
		)
		(duplicate_pad_numbers_are_jumpers no)
		(fp_line
			(start 1.905 -1.651)
			(end 1.905 1.651)
			(stroke
				(width 0.1524)
				(type default)
			)
			(layer "F.SilkS")
		)
		(fp_line
			(start -1.905 -1.651)
			(end 1.905 -1.651)
			(stroke
				(width 0.1524)
				(type default)
			)
			(layer "F.SilkS")
		)
		(fp_line
			(start 1.905 1.651)
			(end -1.905 1.651)
			(stroke
				(width 0.1524)
				(type default)
			)
			(layer "F.SilkS")
		)
		(fp_line
			(start -1.905 1.651)
			(end -1.905 -1.651)
			(stroke
				(width 0.1524)
				(type default)
			)
			(layer "F.SilkS")
		)
		(fp_line
			(start 0.6985 -1.524)
			(end 0.6985 -0.219964)
			(stroke
				(width 0.1)
				(type default)
			)
			(layer "F.Fab")
		)
		(fp_line
			(start -0.649986 -1.524)
			(end 0.6985 -1.524)
			(stroke
				(width 0.1)
				(type default)
			)
			(layer "F.Fab")
		)
		(fp_line
			(start -0.649986 -1.169924)
			(end -0.649986 -1.524)
			(stroke
				(width 0.1)
				(type default)
			)
			(layer "F.Fab")
		)
		(fp_line
			(start -1.249934 -1.169924)
			(end -0.649986 -1.169924)
			(stroke
				(width 0.1)
				(type default)
			)
			(layer "F.Fab")
		)
		(fp_line
			(start -0.6985 -0.729996)
			(end -1.249934 -0.729996)
			(stroke
				(width 0.1)
				(type default)
			)
			(layer "F.Fab")
		)
		(fp_line
			(start -1.249934 -0.729996)
			(end -1.249934 -1.169924)
			(stroke
				(width 0.1)
				(type default)
			)
			(layer "F.Fab")
		)
		(fp_line
			(start 1.249934 -0.219964)
			(end 1.249934 0.219964)
			(stroke
				(width 0.1)
				(type default)
			)
			(layer "F.Fab")
		)
		(fp_line
			(start 0.6985 -0.219964)
			(end 1.249934 -0.219964)
			(stroke
				(width 0.1)
				(type default)
			)
			(layer "F.Fab")
		)
		(fp_line
			(start 1.249934 0.219964)
			(end 0.6985 0.219964)
			(stroke
				(width 0.1)
				(type default)
			)
			(layer "F.Fab")
		)
		(fp_line
			(start 0.6985 0.219964)
			(end 0.6985 1.524)
			(stroke
				(width 0.1)
				(type default)
			)
			(layer "F.Fab")
		)
		(fp_line
			(start -0.6985 0.729996)
			(end -0.6985 -0.729996)
			(stroke
				(width 0.1)
				(type default)
			)
			(layer "F.Fab")
		)
		(fp_line
			(start -1.249934 0.729996)
			(end -0.6985 0.729996)
			(stroke
				(width 0.1)
				(type default)
			)
			(layer "F.Fab")
		)
		(fp_line
			(start -0.649986 1.169924)
			(end -1.249934 1.169924)
			(stroke
				(width 0.1)
				(type default)
			)
			(layer "F.Fab")
		)
		(fp_line
			(start -1.249934 1.169924)
			(end -1.249934 0.729996)
			(stroke
				(width 0.1)
				(type default)
			)
			(layer "F.Fab")
		)
		(fp_line
			(start 0.6985 1.524)
			(end -0.649986 1.524)
			(stroke
				(width 0.1)
				(type default)
			)
			(layer "F.Fab")
		)
		(fp_line
			(start -0.649986 1.524)
			(end -0.649986 1.169924)
			(stroke
				(width 0.1)
				(type default)
			)
			(layer "F.Fab")
		)
		(pad "B" smd rect
			(at -1.1176 -1.016)
			(size 1.016 1.27)
			(layers "F.Cu" "F.Mask" "F.Paste")
			(net "BJT_Q3_B")
		)
		(pad "C" smd rect
			(at 1.1176 0)
			(size 1.016 1.27)
			(layers "F.Cu" "F.Mask" "F.Paste")
			(net "BJT_Q3_C")
		)
		(pad "E" smd rect
			(at -1.1176 1.016)
			(size 1.016 1.27)
			(layers "F.Cu" "F.Mask" "F.Paste")
			(net "GND")
		)
	)
	(footprint ""
		(layer "F.Cu")
		(at 8.955024 -39.94531 -90)
		(property "Reference" "PL34"
			(at 5.50037 6.228334 90)
			(unlocked yes)
			(layer "F.SilkS")
			(effects
				(font
					(size 0.7874 0.5842)
					(thickness 0.1524)
				)
				(justify left)
			)
		)
		(property "Value" ""
			(at 0 0 270)
			(layer "F.Fab")
			(effects
				(font
					(size 1.27 1.27)
				)
			)
		)
		(duplicate_pad_numbers_are_jumpers no)
		(fp_line
			(start -5.588 5.150104)
			(end 5.588 5.150104)
			(stroke
				(width 0.1524)
				(type default)
			)
			(layer "F.SilkS")
		)
		(fp_line
			(start 5.588 5.150104)
			(end 5.588 1.8034)
			(stroke
				(width 0.1524)
				(type default)
			)
			(layer "F.SilkS")
		)
		(fp_line
			(start -5.588 1.8288)
			(end -5.588 5.150104)
			(stroke
				(width 0.1524)
				(type default)
			)
			(layer "F.SilkS")
		)
		(fp_line
			(start 5.588 -1.8288)
			(end 5.588 -5.150104)
			(stroke
				(width 0.1524)
				(type default)
			)
			(layer "F.SilkS")
		)
		(fp_line
			(start -5.588 -5.150104)
			(end -5.588 -1.8542)
			(stroke
				(width 0.1524)
				(type default)
			)
			(layer "F.SilkS")
		)
		(fp_line
			(start 5.588 -5.150104)
			(end -5.588 -5.150104)
			(stroke
				(width 0.1524)
				(type default)
			)
			(layer "F.SilkS")
		)
		(fp_line
			(start -5.599938 5.150104)
			(end -5.599938 -5.150104)
			(stroke
				(width 0.1)
				(type default)
			)
			(layer "F.Fab")
		)
		(fp_line
			(start 5.599938 5.150104)
			(end -5.599938 5.150104)
			(stroke
				(width 0.1)
				(type default)
			)
			(layer "F.Fab")
		)
		(fp_line
			(start -5.599938 -5.150104)
			(end 5.599938 -5.150104)
			(stroke
				(width 0.1)
				(type default)
			)
			(layer "F.Fab")
		)
		(fp_line
			(start 5.599938 -5.150104)
			(end 5.599938 5.150104)
			(stroke
				(width 0.1)
				(type default)
			)
			(layer "F.Fab")
		)
		(pad "1" smd rect
			(at -4.338828 0 270)
			(size 3.302 3.302)
			(layers "F.Cu" "F.Mask" "F.Paste")
			(net "SW_P5V_AUX_SW")
		)
		(pad "2" smd rect
			(at 4.338828 0 270)
			(size 3.302 3.302)
			(layers "F.Cu" "F.Mask" "F.Paste")
			(net "P5V_AUX")
		)
	)
	(footprint ""
		(layer "F.Cu")
		(at 65.913 -17.653 180)
		(property "Reference" "J13"
			(at -1.651 -1.04267 0)
			(unlocked yes)
			(layer "F.SilkS")
			(effects
				(font
					(size 0.7874 0.5842)
					(thickness 0.1524)
				)
				(justify left)
			)
		)
		(property "Value" ""
			(at 0 0 180)
			(layer "F.Fab")
			(effects
				(font
					(size 1.27 1.27)
				)
			)
		)
		(duplicate_pad_numbers_are_jumpers no)
		(fp_line
			(start 1.249934 3.860038)
			(end 1.249934 0.6477)
			(stroke
				(width 0.1524)
				(type default)
			)
			(layer "F.SilkS")
		)
		(fp_line
			(start 1.249934 -0.6477)
			(end 1.249934 -3.860038)
			(stroke
				(width 0.1524)
				(type default)
			)
			(layer "F.SilkS")
		)
		(fp_line
			(start 1.249934 -3.860038)
			(end -1.249934 -3.860038)
			(stroke
				(width 0.1524)
				(type default)
			)
			(layer "F.SilkS")
		)
		(fp_line
			(start -1.249934 3.860038)
			(end 1.249934 3.860038)
			(stroke
				(width 0.1524)
				(type default)
			)
			(layer "F.SilkS")
		)
		(fp_line
			(start -1.249934 3.1877)
			(end -1.249934 3.860038)
			(stroke
				(width 0.1524)
				(type default)
			)
			(layer "F.SilkS")
		)
		(fp_line
			(start -1.249934 -1.8923)
			(end -1.249934 1.8923)
			(stroke
				(width 0.1524)
				(type default)
			)
			(layer "F.SilkS")
		)
		(fp_line
			(start -1.249934 -3.860038)
			(end -1.249934 -3.1877)
			(stroke
				(width 0.1524)
				(type default)
			)
			(layer "F.SilkS")
		)
		(fp_poly
			(pts
				(xy -4.2164 -3.048) (xy -3.2004 -2.54) (xy -4.2164 -2.032)
			)
			(stroke
				(width 0)
				(type default)
			)
			(fill yes)
			(layer "F.SilkS")
		)
		(fp_line
			(start 1.249934 3.860038)
			(end 1.249934 -3.860038)
			(stroke
				(width 0.1)
				(type default)
			)
			(layer "F.Fab")
		)
		(fp_line
			(start 1.249934 -3.860038)
			(end -1.249934 -3.860038)
			(stroke
				(width 0.1)
				(type default)
			)
			(layer "F.Fab")
		)
		(fp_line
			(start -1.249934 3.860038)
			(end 1.249934 3.860038)
			(stroke
				(width 0.1)
				(type default)
			)
			(layer "F.Fab")
		)
		(fp_line
			(start -1.249934 -3.860038)
			(end -1.249934 3.860038)
			(stroke
				(width 0.1)
				(type default)
			)
			(layer "F.Fab")
		)
		(fp_poly
			(pts
				(xy -4.2164 -3.048) (xy -3.2004 -2.54) (xy -4.2164 -2.032)
			)
			(stroke
				(width 0)
				(type default)
			)
			(fill yes)
			(layer "F.Fab")
		)
		(pad "1" smd rect
			(at -1.374902 -2.54 90)
			(size 1.016 2.7686)
			(layers "F.Cu" "F.Mask" "F.Paste")
			(net "PU_J13_P1")
		)
		(pad "2" smd rect
			(at 1.374902 0 90)
			(size 1.016 2.7686)
			(layers "F.Cu" "F.Mask" "F.Paste")
			(net "FM_DBG_SW_N")
		)
		(pad "3" smd rect
			(at -1.374902 2.54 90)
			(size 1.016 2.7686)
			(layers "F.Cu" "F.Mask" "F.Paste")
			(net "GND")
		)
	)
	(footprint ""
		(layer "F.Cu")
		(at 12.319 -94.488 180)
		(property "Reference" "R536"
			(at 0 0 180)
			(layer "F.SilkS")
			(hide yes)
			(effects
				(font
					(size 1.27 1.27)
				)
			)
		)
		(property "Value" ""
			(at 0 0 180)
			(layer "F.Fab")
			(effects
				(font
					(size 1.27 1.27)
				)
			)
		)
		(duplicate_pad_numbers_are_jumpers no)
		(fp_line
			(start 0.7874 0.4064)
			(end -0.7874 0.4064)
			(stroke
				(width 0.1524)
				(type default)
			)
			(layer "F.SilkS")
		)
		(fp_line
			(start 0.7874 -0.4064)
			(end 0.7874 0.4064)
			(stroke
				(width 0.1524)
				(type default)
			)
			(layer "F.SilkS")
		)
		(fp_line
			(start -0.7874 0.4064)
			(end -0.7874 -0.4064)
			(stroke
				(width 0.1524)
				(type default)
			)
			(layer "F.SilkS")
		)
		(fp_line
			(start -0.7874 -0.4064)
			(end 0.7874 -0.4064)
			(stroke
				(width 0.1524)
				(type default)
			)
			(layer "F.SilkS")
		)
		(fp_line
			(start 0.67945 0.3048)
			(end 0.120396 0.3048)
			(stroke
				(width 0.1)
				(type default)
			)
			(layer "F.Fab")
		)
		(fp_line
			(start 0.67945 -0.3048)
			(end 0.67945 0.3048)
			(stroke
				(width 0.1)
				(type default)
			)
			(layer "F.Fab")
		)
		(fp_line
			(start 0.12065 -0.2794)
			(end 0.12065 -0.3048)
			(stroke
				(width 0.1)
				(type default)
			)
			(layer "F.Fab")
		)
		(fp_line
			(start 0.12065 -0.3048)
			(end 0.67945 -0.3048)
			(stroke
				(width 0.1)
				(type default)
			)
			(layer "F.Fab")
		)
		(fp_line
			(start 0.120396 0.3048)
			(end 0.120396 0.2794)
			(stroke
				(width 0.1)
				(type default)
			)
			(layer "F.Fab")
		)
		(fp_line
			(start 0.120396 0.2794)
			(end -0.12065 0.2794)
			(stroke
				(width 0.1)
				(type default)
			)
			(layer "F.Fab")
		)
		(fp_line
			(start -0.12065 0.3048)
			(end -0.67945 0.3048)
			(stroke
				(width 0.1)
				(type default)
			)
			(layer "F.Fab")
		)
		(fp_line
			(start -0.12065 0.2794)
			(end -0.12065 0.3048)
			(stroke
				(width 0.1)
				(type default)
			)
			(layer "F.Fab")
		)
		(fp_line
			(start -0.12065 -0.2794)
			(end 0.12065 -0.2794)
			(stroke
				(width 0.1)
				(type default)
			)
			(layer "F.Fab")
		)
		(fp_line
			(start -0.12065 -0.305054)
			(end -0.12065 -0.2794)
			(stroke
				(width 0.1)
				(type default)
			)
			(layer "F.Fab")
		)
		(fp_line
			(start -0.67945 0.3048)
			(end -0.67945 -0.305054)
			(stroke
				(width 0.1)
				(type default)
			)
			(layer "F.Fab")
		)
		(fp_line
			(start -0.67945 -0.305054)
			(end -0.12065 -0.305054)
			(stroke
				(width 0.1)
				(type default)
			)
			(layer "F.Fab")
		)
		(pad "1" smd circle
			(at -0.40005 0 180)
			(size 0 0)
			(layers "F.Cu" "F.Mask" "F.Paste")
			(net "BMC_CPLD_GPIO_12_R2")
		)
		(pad "2" smd circle
			(at 0.40005 0 180)
			(size 0 0)
			(layers "F.Cu" "F.Mask" "F.Paste")
			(net "BMC_CPLD_GPIO_12")
		)
	)
)
